(kicad_pcb
	(version 20241229)
	(generator "pcbnew")
	(generator_version "9.0")
	(general
		(thickness 1.599998)
		(legacy_teardrops no)
	)
	(paper "A4")
	(title_block
		(title "Artix - Datacenter Secure Control Module (DC-SCM)")
		(date "2024-11-06")
		(rev "1.1.3")
		(comment 9 "footprints 294-298 of 544")
	)
	(layers
		(0 "F.Cu" signal)
		(4 "In1.Cu" signal)
		(6 "In2.Cu" signal)
		(8 "In3.Cu" signal)
		(10 "In4.Cu" signal)
		(12 "In5.Cu" signal)
		(14 "In6.Cu" signal)
		(2 "B.Cu" signal)
		(9 "F.Adhes" user "F.Adhesive")
		(11 "B.Adhes" user "B.Adhesive")
		(13 "F.Paste" user)
		(15 "B.Paste" user)
		(5 "F.SilkS" user "F.Silkscreen")
		(7 "B.SilkS" user "B.Silkscreen")
		(1 "F.Mask" user)
		(3 "B.Mask" user)
		(17 "Dwgs.User" user "User.Drawings")
		(19 "Cmts.User" user "User.Comments")
		(21 "Eco1.User" user "User.Eco1")
		(23 "Eco2.User" user "User.Eco2")
		(25 "Edge.Cuts" user)
		(27 "Margin" user)
		(31 "F.CrtYd" user "F.Courtyard")
		(29 "B.CrtYd" user "B.Courtyard")
		(35 "F.Fab" user)
		(33 "B.Fab" user)
	)
	(footprint "antmicro-footprints:C_0603_1608Metric"
		(layer "B.Cu")
		(at 96.319 107.177 180)
		(descr "Capacitor SMD 0603")
		(tags "capacitor 0603")
		(property "Reference" "C164"
			(at 1.019 0.177 0)
			(layer "B.SilkS")
			(effects
				(font
					(size 0.7 0.7)
					(thickness 0.15)
				)
				(justify left bottom mirror)
			)
		)
		(property "Value" "C_4u7_0603"
			(at 0 -1.6 0)
			(layer "B.Fab")
			(effects
				(font
					(size 0.7 0.7)
					(thickness 0.15)
				)
				(justify left bottom mirror)
			)
		)
		(property "Datasheet" "https://product.tdk.com/en/search/capacitor/ceramic/mlcc/info?part_no=C1608X5R1V475M080AC"
			(at 0 0 180)
			(layer "F.Fab")
			(hide yes)
			(effects
				(font
					(size 1.27 1.27)
					(thickness 0.15)
				)
			)
		)
		(property "Description" "SMD Multilayer Ceramic Capacitor, 4.7 µF, 35 V, 0603 [1608 Metric], ± 20%, X5R, C"
			(at 0 0 180)
			(layer "F.Fab")
			(hide yes)
			(effects
				(font
					(size 1.27 1.27)
					(thickness 0.15)
				)
			)
		)
		(property "Author" "Antmicro"
			(at 192.638 214.354 0)
			(layer "B.Fab")
			(hide yes)
			(effects
				(font
					(size 1 1)
					(thickness 0.15)
				)
				(justify mirror)
			)
		)
		(property "Dielectric" ""
			(at 192.638 214.354 0)
			(layer "B.Fab")
			(hide yes)
			(effects
				(font
					(size 1 1)
					(thickness 0.15)
				)
				(justify mirror)
			)
		)
		(property "License" "Apache-2.0"
			(at 192.638 214.354 0)
			(layer "B.Fab")
			(hide yes)
			(effects
				(font
					(size 1 1)
					(thickness 0.15)
				)
				(justify mirror)
			)
		)
		(property "MPN" "C1608X5R1V475M080AC"
			(at 192.638 214.354 0)
			(layer "B.Fab")
			(hide yes)
			(effects
				(font
					(size 1 1)
					(thickness 0.15)
				)
				(justify mirror)
			)
		)
		(property "Manufacturer" "TDK"
			(at 192.638 214.354 0)
			(layer "B.Fab")
			(hide yes)
			(effects
				(font
					(size 1 1)
					(thickness 0.15)
				)
				(justify mirror)
			)
		)
		(property "Val" "4u7"
			(at 192.638 214.354 0)
			(layer "B.Fab")
			(hide yes)
			(effects
				(font
					(size 1 1)
					(thickness 0.15)
				)
				(justify mirror)
			)
		)
		(property "Voltage" ""
			(at 192.638 214.354 0)
			(layer "B.Fab")
			(hide yes)
			(effects
				(font
					(size 1 1)
					(thickness 0.15)
				)
				(justify mirror)
			)
		)
		(property "DNP" ""
			(at 0 0 180)
			(unlocked yes)
			(layer "B.Fab")
			(hide yes)
			(effects
				(font
					(size 1 1)
					(thickness 0.15)
				)
				(justify mirror)
			)
		)
		(sheetname "/FPGA power supply/")
		(sheetfile "fpga-power-supply.kicad_sch")
		(attr smd)
		(fp_line
			(start -0.15 0.4)
			(end 0.15 0.4)
			(stroke
				(width 0.15)
				(type solid)
			)
			(layer "B.SilkS")
		)
		(fp_line
			(start -0.15 -0.4)
			(end 0.15 -0.4)
			(stroke
				(width 0.15)
				(type solid)
			)
			(layer "B.SilkS")
		)
		(fp_rect
			(start -1.25 0.65)
			(end 1.25 -0.65)
			(stroke
				(width 0.05)
				(type solid)
			)
			(fill no)
			(layer "B.CrtYd")
		)
		(fp_rect
			(start -0.8 0.4)
			(end 0.8 -0.4)
			(stroke
				(width 0.15)
				(type solid)
			)
			(fill no)
			(layer "B.Fab")
		)
		(pad "1" smd roundrect
			(at -0.7 0 180)
			(size 0.8 1)
			(layers "B.Cu" "B.Mask" "B.Paste")
			(roundrect_rratio 0.2)
			(net 1 "GND")
			(pintype "passive")
		)
		(pad "2" smd roundrect
			(at 0.7 0 180)
			(size 0.8 1)
			(layers "B.Cu" "B.Mask" "B.Paste")
			(roundrect_rratio 0.2)
			(net 6 "VCC1V0")
			(pintype "passive")
		)
	)
	(footprint "antmicro-footprints:C_0603_1608Metric"
		(layer "B.Cu")
		(at 96.369 105.677 180)
		(descr "Capacitor SMD 0603")
		(tags "capacitor 0603")
		(property "Reference" "C158"
			(at 1.009 -0.223 0)
			(layer "B.SilkS")
			(effects
				(font
					(size 0.7 0.7)
					(thickness 0.15)
				)
				(justify left bottom mirror)
			)
		)
		(property "Value" "C_4u7_0603"
			(at 0 -1.6 0)
			(layer "B.Fab")
			(effects
				(font
					(size 0.7 0.7)
					(thickness 0.15)
				)
				(justify left bottom mirror)
			)
		)
		(property "Datasheet" "https://product.tdk.com/en/search/capacitor/ceramic/mlcc/info?part_no=C1608X5R1V475M080AC"
			(at 0 0 180)
			(layer "F.Fab")
			(hide yes)
			(effects
				(font
					(size 1.27 1.27)
					(thickness 0.15)
				)
			)
		)
		(property "Description" "SMD Multilayer Ceramic Capacitor, 4.7 µF, 35 V, 0603 [1608 Metric], ± 20%, X5R, C"
			(at 0 0 180)
			(layer "F.Fab")
			(hide yes)
			(effects
				(font
					(size 1.27 1.27)
					(thickness 0.15)
				)
			)
		)
		(property "Author" "Antmicro"
			(at 192.738 211.354 0)
			(layer "B.Fab")
			(hide yes)
			(effects
				(font
					(size 1 1)
					(thickness 0.15)
				)
				(justify mirror)
			)
		)
		(property "Dielectric" ""
			(at 192.738 211.354 0)
			(layer "B.Fab")
			(hide yes)
			(effects
				(font
					(size 1 1)
					(thickness 0.15)
				)
				(justify mirror)
			)
		)
		(property "License" "Apache-2.0"
			(at 192.738 211.354 0)
			(layer "B.Fab")
			(hide yes)
			(effects
				(font
					(size 1 1)
					(thickness 0.15)
				)
				(justify mirror)
			)
		)
		(property "MPN" "C1608X5R1V475M080AC"
			(at 192.738 211.354 0)
			(layer "B.Fab")
			(hide yes)
			(effects
				(font
					(size 1 1)
					(thickness 0.15)
				)
				(justify mirror)
			)
		)
		(property "Manufacturer" "TDK"
			(at 192.738 211.354 0)
			(layer "B.Fab")
			(hide yes)
			(effects
				(font
					(size 1 1)
					(thickness 0.15)
				)
				(justify mirror)
			)
		)
		(property "Val" "4u7"
			(at 192.738 211.354 0)
			(layer "B.Fab")
			(hide yes)
			(effects
				(font
					(size 1 1)
					(thickness 0.15)
				)
				(justify mirror)
			)
		)
		(property "Voltage" ""
			(at 192.738 211.354 0)
			(layer "B.Fab")
			(hide yes)
			(effects
				(font
					(size 1 1)
					(thickness 0.15)
				)
				(justify mirror)
			)
		)
		(property "DNP" ""
			(at 0 0 180)
			(unlocked yes)
			(layer "B.Fab")
			(hide yes)
			(effects
				(font
					(size 1 1)
					(thickness 0.15)
				)
				(justify mirror)
			)
		)
		(sheetname "/FPGA power supply/")
		(sheetfile "fpga-power-supply.kicad_sch")
		(attr smd)
		(fp_line
			(start -0.15 0.4)
			(end 0.15 0.4)
			(stroke
				(width 0.15)
				(type solid)
			)
			(layer "B.SilkS")
		)
		(fp_line
			(start -0.15 -0.4)
			(end 0.15 -0.4)
			(stroke
				(width 0.15)
				(type solid)
			)
			(layer "B.SilkS")
		)
		(fp_rect
			(start -1.25 0.65)
			(end 1.25 -0.65)
			(stroke
				(width 0.05)
				(type solid)
			)
			(fill no)
			(layer "B.CrtYd")
		)
		(fp_rect
			(start -0.8 0.4)
			(end 0.8 -0.4)
			(stroke
				(width 0.15)
				(type solid)
			)
			(fill no)
			(layer "B.Fab")
		)
		(pad "1" smd roundrect
			(at -0.7 0 180)
			(size 0.8 1)
			(layers "B.Cu" "B.Mask" "B.Paste")
			(roundrect_rratio 0.2)
			(net 1 "GND")
			(pintype "passive")
		)
		(pad "2" smd roundrect
			(at 0.7 0 180)
			(size 0.8 1)
			(layers "B.Cu" "B.Mask" "B.Paste")
			(roundrect_rratio 0.2)
			(net 6 "VCC1V0")
			(pintype "passive")
		)
	)
	(footprint "antmicro-footprints:C_0603_1608Metric"
		(layer "B.Cu")
		(at 96.309 108.677 180)
		(descr "Capacitor SMD 0603")
		(tags "capacitor 0603")
		(property "Reference" "C160"
			(at 1.009 0.577 0)
			(layer "B.SilkS")
			(effects
				(font
					(size 0.7 0.7)
					(thickness 0.15)
				)
				(justify left bottom mirror)
			)
		)
		(property "Value" "C_4u7_0603"
			(at 0 -1.6 0)
			(layer "B.Fab")
			(effects
				(font
					(size 0.7 0.7)
					(thickness 0.15)
				)
				(justify left bottom mirror)
			)
		)
		(property "Datasheet" "https://product.tdk.com/en/search/capacitor/ceramic/mlcc/info?part_no=C1608X5R1V475M080AC"
			(at 0 0 180)
			(layer "F.Fab")
			(hide yes)
			(effects
				(font
					(size 1.27 1.27)
					(thickness 0.15)
				)
			)
		)
		(property "Description" "SMD Multilayer Ceramic Capacitor, 4.7 µF, 35 V, 0603 [1608 Metric], ± 20%, X5R, C"
			(at 0 0 180)
			(layer "F.Fab")
			(hide yes)
			(effects
				(font
					(size 1.27 1.27)
					(thickness 0.15)
				)
			)
		)
		(property "Author" "Antmicro"
			(at 192.618 217.354 0)
			(layer "B.Fab")
			(hide yes)
			(effects
				(font
					(size 1 1)
					(thickness 0.15)
				)
				(justify mirror)
			)
		)
		(property "Dielectric" ""
			(at 192.618 217.354 0)
			(layer "B.Fab")
			(hide yes)
			(effects
				(font
					(size 1 1)
					(thickness 0.15)
				)
				(justify mirror)
			)
		)
		(property "License" "Apache-2.0"
			(at 192.618 217.354 0)
			(layer "B.Fab")
			(hide yes)
			(effects
				(font
					(size 1 1)
					(thickness 0.15)
				)
				(justify mirror)
			)
		)
		(property "MPN" "C1608X5R1V475M080AC"
			(at 192.618 217.354 0)
			(layer "B.Fab")
			(hide yes)
			(effects
				(font
					(size 1 1)
					(thickness 0.15)
				)
				(justify mirror)
			)
		)
		(property "Manufacturer" "TDK"
			(at 192.618 217.354 0)
			(layer "B.Fab")
			(hide yes)
			(effects
				(font
					(size 1 1)
					(thickness 0.15)
				)
				(justify mirror)
			)
		)
		(property "Val" "4u7"
			(at 192.618 217.354 0)
			(layer "B.Fab")
			(hide yes)
			(effects
				(font
					(size 1 1)
					(thickness 0.15)
				)
				(justify mirror)
			)
		)
		(property "Voltage" ""
			(at 192.618 217.354 0)
			(layer "B.Fab")
			(hide yes)
			(effects
				(font
					(size 1 1)
					(thickness 0.15)
				)
				(justify mirror)
			)
		)
		(property "DNP" ""
			(at 0 0 180)
			(unlocked yes)
			(layer "B.Fab")
			(hide yes)
			(effects
				(font
					(size 1 1)
					(thickness 0.15)
				)
				(justify mirror)
			)
		)
		(sheetname "/FPGA power supply/")
		(sheetfile "fpga-power-supply.kicad_sch")
		(attr smd)
		(fp_line
			(start -0.15 0.4)
			(end 0.15 0.4)
			(stroke
				(width 0.15)
				(type solid)
			)
			(layer "B.SilkS")
		)
		(fp_line
			(start -0.15 -0.4)
			(end 0.15 -0.4)
			(stroke
				(width 0.15)
				(type solid)
			)
			(layer "B.SilkS")
		)
		(fp_rect
			(start -1.25 0.65)
			(end 1.25 -0.65)
			(stroke
				(width 0.05)
				(type solid)
			)
			(fill no)
			(layer "B.CrtYd")
		)
		(fp_rect
			(start -0.8 0.4)
			(end 0.8 -0.4)
			(stroke
				(width 0.15)
				(type solid)
			)
			(fill no)
			(layer "B.Fab")
		)
		(pad "1" smd roundrect
			(at -0.7 0 180)
			(size 0.8 1)
			(layers "B.Cu" "B.Mask" "B.Paste")
			(roundrect_rratio 0.2)
			(net 1 "GND")
			(pintype "passive")
		)
		(pad "2" smd roundrect
			(at 0.7 0 180)
			(size 0.8 1)
			(layers "B.Cu" "B.Mask" "B.Paste")
			(roundrect_rratio 0.2)
			(net 6 "VCC1V0")
			(pintype "passive")
		)
	)
	(footprint "antmicro-footprints:C_0603_1608Metric"
		(layer "B.Cu")
		(at 112.6 104.8 180)
		(descr "Capacitor SMD 0603")
		(tags "capacitor 0603")
		(property "Reference" "C99"
			(at -3.3 -0.351 0)
			(layer "B.SilkS")
			(effects
				(font
					(size 0.7 0.7)
					(thickness 0.15)
				)
				(justify left bottom mirror)
			)
		)
		(property "Value" "C_4u7_0603"
			(at 0 -1.6 0)
			(layer "B.Fab")
			(effects
				(font
					(size 0.7 0.7)
					(thickness 0.15)
				)
				(justify left bottom mirror)
			)
		)
		(property "Datasheet" "https://product.tdk.com/en/search/capacitor/ceramic/mlcc/info?part_no=C1608X5R1V475M080AC"
			(at 0 0 180)
			(layer "F.Fab")
			(hide yes)
			(effects
				(font
					(size 1.27 1.27)
					(thickness 0.15)
				)
			)
		)
		(property "Description" "SMD Multilayer Ceramic Capacitor, 4.7 µF, 35 V, 0603 [1608 Metric], ± 20%, X5R, C"
			(at 0 0 180)
			(layer "F.Fab")
			(hide yes)
			(effects
				(font
					(size 1.27 1.27)
					(thickness 0.15)
				)
			)
		)
		(property "Author" "Antmicro"
			(at 225.2 209.6 0)
			(layer "B.Fab")
			(hide yes)
			(effects
				(font
					(size 1 1)
					(thickness 0.15)
				)
				(justify mirror)
			)
		)
		(property "Dielectric" ""
			(at 225.2 209.6 0)
			(layer "B.Fab")
			(hide yes)
			(effects
				(font
					(size 1 1)
					(thickness 0.15)
				)
				(justify mirror)
			)
		)
		(property "License" "Apache-2.0"
			(at 225.2 209.6 0)
			(layer "B.Fab")
			(hide yes)
			(effects
				(font
					(size 1 1)
					(thickness 0.15)
				)
				(justify mirror)
			)
		)
		(property "MPN" "C1608X5R1V475M080AC"
			(at 225.2 209.6 0)
			(layer "B.Fab")
			(hide yes)
			(effects
				(font
					(size 1 1)
					(thickness 0.15)
				)
				(justify mirror)
			)
		)
		(property "Manufacturer" "TDK"
			(at 225.2 209.6 0)
			(layer "B.Fab")
			(hide yes)
			(effects
				(font
					(size 1 1)
					(thickness 0.15)
				)
				(justify mirror)
			)
		)
		(property "Val" "4u7"
			(at 225.2 209.6 0)
			(layer "B.Fab")
			(hide yes)
			(effects
				(font
					(size 1 1)
					(thickness 0.15)
				)
				(justify mirror)
			)
		)
		(property "Voltage" ""
			(at 225.2 209.6 0)
			(layer "B.Fab")
			(hide yes)
			(effects
				(font
					(size 1 1)
					(thickness 0.15)
				)
				(justify mirror)
			)
		)
		(sheetname "/FPGA banks 13-16/")
		(sheetfile "fpga-banks-13-16.kicad_sch")
		(attr smd)
		(fp_line
			(start -0.15 0.4)
			(end 0.15 0.4)
			(stroke
				(width 0.15)
				(type solid)
			)
			(layer "B.SilkS")
		)
		(fp_line
			(start -0.15 -0.4)
			(end 0.15 -0.4)
			(stroke
				(width 0.15)
				(type solid)
			)
			(layer "B.SilkS")
		)
		(fp_rect
			(start -1.25 0.65)
			(end 1.25 -0.65)
			(stroke
				(width 0.05)
				(type solid)
			)
			(fill no)
			(layer "B.CrtYd")
		)
		(fp_rect
			(start -0.8 0.4)
			(end 0.8 -0.4)
			(stroke
				(width 0.15)
				(type solid)
			)
			(fill no)
			(layer "B.Fab")
		)
		(pad "1" smd roundrect
			(at -0.7 0 180)
			(size 0.8 1)
			(layers "B.Cu" "B.Mask" "B.Paste")
			(roundrect_rratio 0.2)
			(net 1 "GND")
			(pintype "passive")
		)
		(pad "2" smd roundrect
			(at 0.7 0 180)
			(size 0.8 1)
			(layers "B.Cu" "B.Mask" "B.Paste")
			(roundrect_rratio 0.2)
			(net 2 "VCC3V3")
			(pintype "passive")
		)
	)
	(footprint "antmicro-footprints:C_0201"
		(layer "B.Cu")
		(at 106.875 120.375 -90)
		(descr "Capacitor SMD 0201")
		(tags "capacitor SMD 0201")
		(property "Reference" "C161"
			(at -1.375 -1.225 90)
			(layer "B.SilkS")
			(effects
				(font
					(size 0.7 0.7)
					(thickness 0.15)
				)
				(justify left bottom mirror)
			)
		)
		(property "Value" "C_470n_0201"
			(at 0 -1.4 90)
			(layer "B.Fab")
			(effects
				(font
					(size 0.7 0.7)
					(thickness 0.15)
				)
				(justify left bottom mirror)
			)
		)
		(property "Datasheet" "https://product.tdk.com/en/search/capacitor/ceramic/mlcc/info?part_no=C0603X5R1A474M030BC"
			(at 0 0 270)
			(layer "F.Fab")
			(hide yes)
			(effects
				(font
					(size 1.27 1.27)
					(thickness 0.15)
				)
			)
		)
		(property "Description" "SMD Multilayer Ceramic Capacitor, 0.47 µF, 10 V, 0201 [0603 Metric], ± 20%, X5R, C"
			(at 0 0 270)
			(layer "F.Fab")
			(hide yes)
			(effects
				(font
					(size 1.27 1.27)
					(thickness 0.15)
				)
			)
		)
		(property "Author" "Antmicro"
			(at -13.5 227.25 0)
			(layer "B.Fab")
			(hide yes)
			(effects
				(font
					(size 1 1)
					(thickness 0.15)
				)
				(justify mirror)
			)
		)
		(property "Dielectric" ""
			(at -13.5 227.25 0)
			(layer "B.Fab")
			(hide yes)
			(effects
				(font
					(size 1 1)
					(thickness 0.15)
				)
				(justify mirror)
			)
		)
		(property "License" "Apache-2.0"
			(at -13.5 227.25 0)
			(layer "B.Fab")
			(hide yes)
			(effects
				(font
					(size 1 1)
					(thickness 0.15)
				)
				(justify mirror)
			)
		)
		(property "MPN" "C0603X5R1A474M030BC"
			(at -13.5 227.25 0)
			(layer "B.Fab")
			(hide yes)
			(effects
				(font
					(size 1 1)
					(thickness 0.15)
				)
				(justify mirror)
			)
		)
		(property "Manufacturer" "TDK"
			(at -13.5 227.25 0)
			(layer "B.Fab")
			(hide yes)
			(effects
				(font
					(size 1 1)
					(thickness 0.15)
				)
				(justify mirror)
			)
		)
		(property "Public" "False"
			(at -13.5 227.25 0)
			(layer "B.Fab")
			(hide yes)
			(effects
				(font
					(size 1 1)
					(thickness 0.15)
				)
				(justify mirror)
			)
		)
		(property "Val" "470n"
			(at -13.5 227.25 0)
			(layer "B.Fab")
			(hide yes)
			(effects
				(font
					(size 1 1)
					(thickness 0.15)
				)
				(justify mirror)
			)
		)
		(property "Voltage" ""
			(at -13.5 227.25 0)
			(layer "B.Fab")
			(hide yes)
			(effects
				(font
					(size 1 1)
					(thickness 0.15)
				)
				(justify mirror)
			)
		)
		(property "DNP" ""
			(at 0 0 270)
			(unlocked yes)
			(layer "B.Fab")
			(hide yes)
			(effects
				(font
					(size 1 1)
					(thickness 0.15)
				)
				(justify mirror)
			)
		)
		(sheetname "/FPGA power supply/")
		(sheetfile "fpga-power-supply.kicad_sch")
		(attr smd)
		(fp_rect
			(start -0.7 0.35)
			(end 0.7 -0.35)
			(stroke
				(width 0.05)
				(type default)
			)
			(fill no)
			(layer "B.CrtYd")
		)
		(fp_rect
			(start 0.3 -0.15)
			(end -0.301 0.149)
			(stroke
				(width 0.15)
				(type solid)
			)
			(fill no)
			(layer "B.Fab")
		)
		(pad "" smd roundrect
			(at -0.349 0.002 270)
			(size 0.318 0.36)
			(layers "B.Paste")
			(roundrect_rratio 0.25)
		)
		(pad "" smd roundrect
			(at 0.341 0.002 270)
			(size 0.318 0.36)
			(layers "B.Paste")
			(roundrect_rratio 0.25)
		)
		(pad "1" smd roundrect
			(at -0.321 0.002 270)
			(size 0.46 0.4)
			(layers "B.Cu" "B.Mask")
			(roundrect_rratio 0.25)
			(net 1 "GND")
			(pintype "passive")
		)
		(pad "2" smd roundrect
			(at 0.32 0.002 270)
			(size 0.46 0.4)
			(layers "B.Cu" "B.Mask")
			(roundrect_rratio 0.25)
			(net 6 "VCC1V0")
			(pintype "passive")
		)
	)
)
